# T6G (Grand Teton) — schematic netlist excerpt (pin names and nets, part order shuffled) for the footprints in the layout excerpt that follows; sources: Cadence DE-HDL packaged netlist, KiCad conversion of 04192023_DAF0TMB3IC0_F0TG_MB_C_brd_V02_OCP.brd

PR205  Q_RES  2.2 1% CHIP  pkg 0402LF  page 215 : A = PVDDCR_CPU0_P1_PVCC ; B = PVDDCR_SOC_P1_VCC1
R304  Q_RES  1K 1% CHIP  pkg 0402LF  page 99 : A = PWRGD_CHB_CPU1_DIMM ; B = PWRGD_CHAF_CPU1
C526  Q_CAP  1UF 4V 20% X6S  pkg 0201  page 279 : A = P0V9_CPU0_RT0_2A ; B = GND

(kicad_pcb
	(version 20260206)
	(generator "pcbnew")
	(generator_version "10.0")
	(general
		(thickness 1.6)
		(legacy_teardrops no)
	)
	(paper "A4")
	(title_block
		(title "04192023_DAF0TMB3IC0_F0TG_MB_C_brd_V02_OCP.brd")
		(comment 1 "Grand Teton / footprints 7380-7382 of 8354")
	)
	(layers
		(0 "F.Cu" signal "TOP")
		(4 "In1.Cu" signal "GND")
		(6 "In2.Cu" signal "IN1")
		(8 "In3.Cu" signal "GND1")
		(10 "In4.Cu" signal "IN2")
		(12 "In5.Cu" signal "GND2")
		(14 "In6.Cu" signal "IN3")
		(16 "In7.Cu" signal "GND3")
		(18 "In8.Cu" signal "VCC")
		(20 "In9.Cu" signal "VCC1")
		(22 "In10.Cu" signal "GND4")
		(24 "In11.Cu" signal "IN4")
		(26 "In12.Cu" signal "GND5")
		(28 "In13.Cu" signal "IN5")
		(30 "In14.Cu" signal "GND6")
		(32 "In15.Cu" signal "IN6")
		(34 "In16.Cu" signal "GND7")
		(2 "B.Cu" signal "BOTTOM")
		(9 "F.Adhes" user "F.Adhesive")
		(11 "B.Adhes" user "B.Adhesive")
		(13 "F.Paste" user "Package Geometry/Pastemask Top")
		(15 "B.Paste" user "Package Geometry/Pastemask Bottom")
		(5 "F.SilkS" user "Ref Des/Silkscreen Top")
		(7 "B.SilkS" user "Ref Des/Silkscreen Bottom")
		(1 "F.Mask" user "Board Geometry/Soldermask Top")
		(3 "B.Mask" user "Board Geometry/Soldermask Bottom")
		(17 "Dwgs.User" user "User.Drawings")
		(19 "Cmts.User" user "User.Comments")
		(21 "Eco1.User" user "User.Eco1")
		(23 "Eco2.User" user "User.Eco2")
		(25 "Edge.Cuts" user "Board Geometry/Outline")
		(27 "Margin" user)
		(31 "F.CrtYd" user "Package Geometry/Place Bound Top")
		(29 "B.CrtYd" user "Package Geometry/Place Bound Bottom")
		(35 "F.Fab" user "Ref Des/Assembly Top")
		(33 "B.Fab" user "Ref Des/Assembly Bottom")
	)
	(footprint ""
		(layer "B.Cu")
		(at 117.996462 -170.864276 90)
		(property "Reference" "PR205"
			(at 0 0 90)
			(layer "B.SilkS")
			(hide yes)
			(effects
				(font
					(size 1.27 1.27)
				)
				(justify mirror)
			)
		)
		(property "Value" ""
			(at 0 0 90)
			(layer "B.Fab")
			(effects
				(font
					(size 1.27 1.27)
				)
				(justify mirror)
			)
		)
		(duplicate_pad_numbers_are_jumpers no)
		(fp_line
			(start 0.7874 -0.4064)
			(end -0.7874 -0.4064)
			(stroke
				(width 0.1524)
				(type default)
			)
			(layer "B.SilkS")
		)
		(fp_line
			(start -0.7874 -0.4064)
			(end -0.7874 0.4064)
			(stroke
				(width 0.1524)
				(type default)
			)
			(layer "B.SilkS")
		)
		(fp_line
			(start 0.7874 0.4064)
			(end 0.7874 -0.4064)
			(stroke
				(width 0.1524)
				(type default)
			)
			(layer "B.SilkS")
		)
		(fp_line
			(start -0.7874 0.4064)
			(end 0.7874 0.4064)
			(stroke
				(width 0.1524)
				(type default)
			)
			(layer "B.SilkS")
		)
		(fp_line
			(start 0.67945 -0.305054)
			(end 0.12065 -0.305054)
			(stroke
				(width 0.1)
				(type default)
			)
			(layer "B.Fab")
		)
		(fp_line
			(start 0.12065 -0.305054)
			(end 0.12065 -0.2794)
			(stroke
				(width 0.1)
				(type default)
			)
			(layer "B.Fab")
		)
		(fp_line
			(start -0.12065 -0.3048)
			(end -0.67945 -0.3048)
			(stroke
				(width 0.1)
				(type default)
			)
			(layer "B.Fab")
		)
		(fp_line
			(start -0.67945 -0.3048)
			(end -0.67945 0.3048)
			(stroke
				(width 0.1)
				(type default)
			)
			(layer "B.Fab")
		)
		(fp_line
			(start 0.12065 -0.2794)
			(end -0.12065 -0.2794)
			(stroke
				(width 0.1)
				(type default)
			)
			(layer "B.Fab")
		)
		(fp_line
			(start -0.12065 -0.2794)
			(end -0.12065 -0.3048)
			(stroke
				(width 0.1)
				(type default)
			)
			(layer "B.Fab")
		)
		(fp_line
			(start 0.12065 0.2794)
			(end 0.12065 0.3048)
			(stroke
				(width 0.1)
				(type default)
			)
			(layer "B.Fab")
		)
		(fp_line
			(start -0.120396 0.2794)
			(end 0.12065 0.2794)
			(stroke
				(width 0.1)
				(type default)
			)
			(layer "B.Fab")
		)
		(fp_line
			(start 0.67945 0.3048)
			(end 0.67945 -0.305054)
			(stroke
				(width 0.1)
				(type default)
			)
			(layer "B.Fab")
		)
		(fp_line
			(start 0.12065 0.3048)
			(end 0.67945 0.3048)
			(stroke
				(width 0.1)
				(type default)
			)
			(layer "B.Fab")
		)
		(fp_line
			(start -0.120396 0.3048)
			(end -0.120396 0.2794)
			(stroke
				(width 0.1)
				(type default)
			)
			(layer "B.Fab")
		)
		(fp_line
			(start -0.67945 0.3048)
			(end -0.120396 0.3048)
			(stroke
				(width 0.1)
				(type default)
			)
			(layer "B.Fab")
		)
		(pad "1" smd circle
			(at 0.40005 0 270)
			(size 0 0)
			(layers "B.Cu" "B.Mask" "B.Paste")
			(net "PVDDCR_CPU0_P1_PVCC")
		)
		(pad "2" smd circle
			(at -0.40005 0 270)
			(size 0 0)
			(layers "B.Cu" "B.Mask" "B.Paste")
			(net "PVDDCR_SOC_P1_VCC1")
		)
	)
	(footprint ""
		(layer "B.Cu")
		(at 47.538386 -190.948564 180)
		(property "Reference" "R304"
			(at 0 0 0)
			(layer "B.SilkS")
			(hide yes)
			(effects
				(font
					(size 1.27 1.27)
				)
				(justify mirror)
			)
		)
		(property "Value" ""
			(at 0 0 0)
			(layer "B.Fab")
			(effects
				(font
					(size 1.27 1.27)
				)
				(justify mirror)
			)
		)
		(duplicate_pad_numbers_are_jumpers no)
		(fp_line
			(start 0.7874 0.4064)
			(end 0.7874 -0.4064)
			(stroke
				(width 0.1524)
				(type default)
			)
			(layer "B.SilkS")
		)
		(fp_line
			(start 0.7874 -0.4064)
			(end -0.7874 -0.4064)
			(stroke
				(width 0.1524)
				(type default)
			)
			(layer "B.SilkS")
		)
		(fp_line
			(start -0.7874 0.4064)
			(end 0.7874 0.4064)
			(stroke
				(width 0.1524)
				(type default)
			)
			(layer "B.SilkS")
		)
		(fp_line
			(start -0.7874 -0.4064)
			(end -0.7874 0.4064)
			(stroke
				(width 0.1524)
				(type default)
			)
			(layer "B.SilkS")
		)
		(fp_line
			(start 0.67945 0.3048)
			(end 0.67945 -0.305054)
			(stroke
				(width 0.1)
				(type default)
			)
			(layer "B.Fab")
		)
		(fp_line
			(start 0.67945 -0.305054)
			(end 0.12065 -0.305054)
			(stroke
				(width 0.1)
				(type default)
			)
			(layer "B.Fab")
		)
		(fp_line
			(start 0.12065 0.3048)
			(end 0.67945 0.3048)
			(stroke
				(width 0.1)
				(type default)
			)
			(layer "B.Fab")
		)
		(fp_line
			(start 0.12065 0.2794)
			(end 0.12065 0.3048)
			(stroke
				(width 0.1)
				(type default)
			)
			(layer "B.Fab")
		)
		(fp_line
			(start 0.12065 -0.2794)
			(end -0.12065 -0.2794)
			(stroke
				(width 0.1)
				(type default)
			)
			(layer "B.Fab")
		)
		(fp_line
			(start 0.12065 -0.305054)
			(end 0.12065 -0.2794)
			(stroke
				(width 0.1)
				(type default)
			)
			(layer "B.Fab")
		)
		(fp_line
			(start -0.120396 0.3048)
			(end -0.120396 0.2794)
			(stroke
				(width 0.1)
				(type default)
			)
			(layer "B.Fab")
		)
		(fp_line
			(start -0.120396 0.2794)
			(end 0.12065 0.2794)
			(stroke
				(width 0.1)
				(type default)
			)
			(layer "B.Fab")
		)
		(fp_line
			(start -0.12065 -0.2794)
			(end -0.12065 -0.3048)
			(stroke
				(width 0.1)
				(type default)
			)
			(layer "B.Fab")
		)
		(fp_line
			(start -0.12065 -0.3048)
			(end -0.67945 -0.3048)
			(stroke
				(width 0.1)
				(type default)
			)
			(layer "B.Fab")
		)
		(fp_line
			(start -0.67945 0.3048)
			(end -0.120396 0.3048)
			(stroke
				(width 0.1)
				(type default)
			)
			(layer "B.Fab")
		)
		(fp_line
			(start -0.67945 -0.3048)
			(end -0.67945 0.3048)
			(stroke
				(width 0.1)
				(type default)
			)
			(layer "B.Fab")
		)
		(pad "1" smd circle
			(at 0.40005 0)
			(size 0 0)
			(layers "B.Cu" "B.Mask" "B.Paste")
			(net "PWRGD_CHB_CPU1_DIMM")
		)
		(pad "2" smd circle
			(at -0.40005 0)
			(size 0 0)
			(layers "B.Cu" "B.Mask" "B.Paste")
			(net "PWRGD_CHAF_CPU1")
		)
	)
	(footprint ""
		(layer "B.Cu")
		(at 305.778408 -395.148562 90)
		(property "Reference" "C526"
			(at 0 0 90)
			(layer "B.SilkS")
			(hide yes)
			(effects
				(font
					(size 1.27 1.27)
				)
				(justify mirror)
			)
		)
		(property "Value" ""
			(at 0 0 90)
			(layer "B.Fab")
			(effects
				(font
					(size 1.27 1.27)
				)
				(justify mirror)
			)
		)
		(duplicate_pad_numbers_are_jumpers no)
		(fp_line
			(start 0.299974 -0.150114)
			(end -0.299974 -0.150114)
			(stroke
				(width 0.1)
				(type default)
			)
			(layer "B.Fab")
		)
		(fp_line
			(start -0.299974 -0.150114)
			(end -0.299974 0.150114)
			(stroke
				(width 0.1)
				(type default)
			)
			(layer "B.Fab")
		)
		(fp_line
			(start 0.299974 0.150114)
			(end 0.299974 -0.150114)
			(stroke
				(width 0.1)
				(type default)
			)
			(layer "B.Fab")
		)
		(fp_line
			(start -0.299974 0.150114)
			(end 0.299974 0.150114)
			(stroke
				(width 0.1)
				(type default)
			)
			(layer "B.Fab")
		)
		(pad "1" smd rect
			(at 0.2667 0 270)
			(size 0.3048 0.381)
			(layers "B.Cu" "B.Mask" "B.Paste")
			(net "P0V9_CPU0_RT0_2A")
		)
		(pad "2" smd rect
			(at -0.2667 0 270)
			(size 0.3048 0.381)
			(layers "B.Cu" "B.Mask" "B.Paste")
			(net "GND")
		)
	)
)
